(kicad_pcb
	(version 20241229)
	(generator "pcbnew")
	(generator_version "9.0")
	(general
		(thickness 1.61)
		(legacy_teardrops no)
	)
	(paper "A3")
	(title_block
		(title "RDIMM DDR5 Tester")
		(date "2026-05-21")
		(rev "2.2.0")
		(company "Antmicro")
		(comment 9 "footprints 513-517 of 796")
	)
	(layers
		(0 "F.Cu" signal)
		(4 "In1.Cu" power)
		(6 "In2.Cu" mixed)
		(8 "In3.Cu" power)
		(10 "In4.Cu" mixed)
		(12 "In5.Cu" power)
		(14 "In6.Cu" mixed)
		(16 "In7.Cu" power)
		(18 "In8.Cu" power)
		(20 "In9.Cu" mixed)
		(22 "In10.Cu" power)
		(2 "B.Cu" signal)
		(9 "F.Adhes" user "F.Adhesive")
		(11 "B.Adhes" user "B.Adhesive")
		(13 "F.Paste" user)
		(15 "B.Paste" user)
		(5 "F.SilkS" user "F.Silkscreen")
		(7 "B.SilkS" user "B.Silkscreen")
		(1 "F.Mask" user)
		(3 "B.Mask" user)
		(17 "Dwgs.User" user "User.Drawings")
		(19 "Cmts.User" user "User.Comments")
		(21 "Eco1.User" user "User.Eco1")
		(23 "Eco2.User" user "User.Eco2")
		(25 "Edge.Cuts" user)
		(27 "Margin" user)
		(31 "F.CrtYd" user "F.Courtyard")
		(29 "B.CrtYd" user "B.Courtyard")
		(35 "F.Fab" user)
		(33 "B.Fab" user)
	)
	(footprint "antmicro-footprints:Fiducial_1mm_Mask2mm"
		(layer "B.Cu")
		(at 259.8 182.15 180)
		(descr "Circular Fiducial, 1mm bare copper, 3mm soldermask opening")
		(tags "fiducial")
		(property "Reference" "FID1002"
			(at -1.865 1.745 0)
			(layer "B.SilkS")
			(hide yes)
			(effects
				(font
					(size 0.7 0.7)
					(thickness 0.15)
				)
				(justify left bottom mirror)
			)
		)
		(property "Value" "Fiducial_1mm_Mask2mm"
			(at 0 -2.2 0)
			(layer "B.Fab")
			(effects
				(font
					(size 0.7 0.7)
					(thickness 0.15)
				)
				(justify left bottom mirror)
			)
		)
		(sheetfile "data-center-rdimm-ddr5-tester.kicad_sch")
		(attr board_only exclude_from_pos_files exclude_from_bom)
		(fp_circle
			(center 0 0)
			(end 1.24 0)
			(stroke
				(width 0.05)
				(type solid)
			)
			(fill no)
			(layer "B.CrtYd")
		)
		(fp_circle
			(center 0 0)
			(end 0.999 0)
			(stroke
				(width 0.15)
				(type solid)
			)
			(fill no)
			(layer "B.Fab")
		)
		(fp_text user "${REFERENCE}"
			(at -1.25 -4.603 0)
			(layer "B.Fab")
			(effects
				(font
					(size 0.7 0.7)
					(thickness 0.15)
				)
				(justify left bottom mirror)
			)
		)
		(fp_text user "License: Apache-2.0"
			(at -1.25 -7.003 0)
			(layer "B.Fab")
			(effects
				(font
					(size 0.7 0.7)
					(thickness 0.15)
				)
				(justify left bottom mirror)
			)
		)
		(fp_text user "Author: Antmicro"
			(at -1.25 -5.803 0)
			(layer "B.Fab")
			(effects
				(font
					(size 0.7 0.7)
					(thickness 0.15)
				)
				(justify left bottom mirror)
			)
		)
		(pad "" smd circle
			(at 0 0 180)
			(size 1 1)
			(layers "B.Cu" "B.Mask")
			(solder_mask_margin 0.5)
			(clearance 0.5)
		)
	)
	(footprint "antmicro-footprints:C_0402_1005Metric"
		(layer "B.Cu")
		(at 134.924499 152.9005 180)
		(descr "Capacitor SMD 0402")
		(tags "capacitor SMD 0402")
		(property "Reference" "C161"
			(at 1.320499 -0.5155 0)
			(layer "B.SilkS")
			(effects
				(font
					(size 0.7 0.7)
					(thickness 0.15)
				)
				(justify left bottom mirror)
			)
		)
		(property "Value" "C_100n_0402"
			(at -1.022927 -2.155213 0)
			(layer "B.Fab")
			(effects
				(font
					(size 0.7 0.7)
					(thickness 0.15)
				)
				(justify left bottom mirror)
			)
		)
		(property "Datasheet" "https://www.murata.com/products/productdetail?partno=GRM155R61H104KE14%23"
			(at 0 0 180)
			(layer "F.Fab")
			(hide yes)
			(effects
				(font
					(size 1.27 1.27)
					(thickness 0.15)
				)
			)
		)
		(property "MPN" "GRM155R61H104KE14D"
			(at 0 0 180)
			(unlocked yes)
			(layer "B.Fab")
			(hide yes)
			(effects
				(font
					(size 1 1)
					(thickness 0.15)
				)
				(justify mirror)
			)
		)
		(property "Manufacturer" "Murata"
			(at 0 0 180)
			(unlocked yes)
			(layer "B.Fab")
			(hide yes)
			(effects
				(font
					(size 1 1)
					(thickness 0.15)
				)
				(justify mirror)
			)
		)
		(property "License" "Apache-2.0"
			(at 0 0 180)
			(unlocked yes)
			(layer "B.Fab")
			(hide yes)
			(effects
				(font
					(size 1 1)
					(thickness 0.15)
				)
				(justify mirror)
			)
		)
		(property "Author" "Antmicro"
			(at 0 0 180)
			(unlocked yes)
			(layer "B.Fab")
			(hide yes)
			(effects
				(font
					(size 1 1)
					(thickness 0.15)
				)
				(justify mirror)
			)
		)
		(property "Val" "100n"
			(at 0 0 180)
			(unlocked yes)
			(layer "B.Fab")
			(hide yes)
			(effects
				(font
					(size 1 1)
					(thickness 0.15)
				)
				(justify mirror)
			)
		)
		(property "Voltage" "50V"
			(at 0 0 180)
			(unlocked yes)
			(layer "B.Fab")
			(hide yes)
			(effects
				(font
					(size 1 1)
					(thickness 0.15)
				)
				(justify mirror)
			)
		)
		(property "Dielectric" "X5R"
			(at 0 0 180)
			(unlocked yes)
			(layer "B.Fab")
			(hide yes)
			(effects
				(font
					(size 1 1)
					(thickness 0.15)
				)
				(justify mirror)
			)
		)
		(sheetname "/Ethernet/")
		(sheetfile "ethernet.kicad_sch")
		(attr smd)
		(fp_rect
			(start -0.925 0.47)
			(end 0.925 -0.47)
			(stroke
				(width 0.05)
				(type default)
			)
			(fill no)
			(layer "B.CrtYd")
		)
		(fp_line
			(start 0.504 0.25)
			(end 0.504 -0.248)
			(stroke
				(width 0.15)
				(type solid)
			)
			(layer "B.Fab")
		)
		(fp_line
			(start 0.504 -0.248)
			(end -0.494 -0.248)
			(stroke
				(width 0.15)
				(type solid)
			)
			(layer "B.Fab")
		)
		(fp_line
			(start -0.494 0.25)
			(end 0.504 0.25)
			(stroke
				(width 0.15)
				(type solid)
			)
			(layer "B.Fab")
		)
		(fp_line
			(start -0.494 -0.248)
			(end -0.494 0.25)
			(stroke
				(width 0.15)
				(type solid)
			)
			(layer "B.Fab")
		)
		(fp_text user "License: Apache-2.0"
			(at -0.939 -5.799 0)
			(layer "B.Fab")
			(effects
				(font
					(size 0.7 0.7)
					(thickness 0.15)
				)
				(justify left bottom mirror)
			)
		)
		(fp_text user "${REFERENCE}"
			(at -0.939 -4.599 0)
			(layer "B.Fab")
			(effects
				(font
					(size 0.7 0.7)
					(thickness 0.15)
				)
				(justify left bottom mirror)
			)
		)
		(fp_text user "Author: Antmicro"
			(at -0.939 -3.399 0)
			(layer "B.Fab")
			(effects
				(font
					(size 0.7 0.7)
					(thickness 0.15)
				)
				(justify left bottom mirror)
			)
		)
		(pad "1" smd roundrect
			(at -0.48 0 180)
			(size 0.59 0.64)
			(layers "B.Cu" "B.Mask" "B.Paste")
			(roundrect_rratio 0.25)
			(net 1 "GND")
			(pintype "passive")
		)
		(pad "2" smd roundrect
			(at 0.48 0 180)
			(size 0.59 0.64)
			(layers "B.Cu" "B.Mask" "B.Paste")
			(roundrect_rratio 0.25)
			(net 797 "+1V8")
			(pintype "passive")
		)
	)
	(footprint "antmicro-footprints:C_0402_1005Metric_EIA"
		(layer "B.Cu")
		(at 185.5 147)
		(descr "Capacitor SMD 0402 (1005 Metric), square (rectangular) end terminal, IPC_7351 nominal, (Body size source: IPC-SM-782 page 76, https://www.pcb-3d.com/wordpress/wp-content/uploads/ipc-sm-782a_amendment_1_and_2.pdf)")
		(tags "capacitor 0402")
		(property "Reference" "C27"
			(at -30.125 -10.3 180)
			(layer "B.SilkS")
			(effects
				(font
					(size 0.7 0.7)
					(thickness 0.15)
				)
				(justify left bottom mirror)
			)
		)
		(property "Value" "C_10u_10V_0402"
			(at 0 -1.169 180)
			(layer "B.Fab")
			(effects
				(font
					(size 0.7 0.7)
					(thickness 0.15)
				)
				(justify left bottom mirror)
			)
		)
		(property "Datasheet" "https://www.murata.com/products/productdetail?partno=GRM155R61A106ME11%23"
			(at 0 0 0)
			(layer "F.Fab")
			(hide yes)
			(effects
				(font
					(size 1.27 1.27)
					(thickness 0.15)
				)
			)
		)
		(property "MPN" "GRM155R61A106ME11D"
			(at 0 0 0)
			(unlocked yes)
			(layer "B.Fab")
			(hide yes)
			(effects
				(font
					(size 1 1)
					(thickness 0.15)
				)
				(justify mirror)
			)
		)
		(property "Manufacturer" "Murata"
			(at 0 0 0)
			(unlocked yes)
			(layer "B.Fab")
			(hide yes)
			(effects
				(font
					(size 1 1)
					(thickness 0.15)
				)
				(justify mirror)
			)
		)
		(property "License" "Apache-2.0"
			(at 0 0 0)
			(unlocked yes)
			(layer "B.Fab")
			(hide yes)
			(effects
				(font
					(size 1 1)
					(thickness 0.15)
				)
				(justify mirror)
			)
		)
		(property "Author" "Antmicro"
			(at 0 0 0)
			(unlocked yes)
			(layer "B.Fab")
			(hide yes)
			(effects
				(font
					(size 1 1)
					(thickness 0.15)
				)
				(justify mirror)
			)
		)
		(property "Val" "10u"
			(at 0 0 0)
			(unlocked yes)
			(layer "B.Fab")
			(hide yes)
			(effects
				(font
					(size 1 1)
					(thickness 0.15)
				)
				(justify mirror)
			)
		)
		(property "Voltage" "10V"
			(at 0 0 0)
			(unlocked yes)
			(layer "B.Fab")
			(hide yes)
			(effects
				(font
					(size 1 1)
					(thickness 0.15)
				)
				(justify mirror)
			)
		)
		(property "Dielectric" "X5R"
			(at 0 0 0)
			(unlocked yes)
			(layer "B.Fab")
			(hide yes)
			(effects
				(font
					(size 1 1)
					(thickness 0.15)
				)
				(justify mirror)
			)
		)
		(sheetname "/FPGA power/")
		(sheetfile "fpga-power.kicad_sch")
		(attr smd)
		(fp_rect
			(start -0.95 0.45)
			(end 0.95 -0.45)
			(stroke
				(width 0.05)
				(type default)
			)
			(fill no)
			(layer "B.CrtYd")
		)
		(fp_line
			(start -0.5 -0.248)
			(end -0.5 0.25)
			(stroke
				(width 0.15)
				(type solid)
			)
			(layer "B.Fab")
		)
		(fp_line
			(start -0.5 0.25)
			(end 0.498 0.25)
			(stroke
				(width 0.15)
				(type solid)
			)
			(layer "B.Fab")
		)
		(fp_line
			(start 0.498 -0.248)
			(end -0.5 -0.248)
			(stroke
				(width 0.15)
				(type solid)
			)
			(layer "B.Fab")
		)
		(fp_line
			(start 0.498 0.25)
			(end 0.498 -0.248)
			(stroke
				(width 0.15)
				(type solid)
			)
			(layer "B.Fab")
		)
		(fp_text user "Author: Antmicro"
			(at -0.9656 -5.569 180)
			(layer "B.Fab")
			(effects
				(font
					(size 0.7 0.7)
					(thickness 0.15)
				)
				(justify left bottom mirror)
			)
		)
		(fp_text user "${REFERENCE}"
			(at -0.9656 -3.169 180)
			(layer "B.Fab")
			(effects
				(font
					(size 0.7 0.7)
					(thickness 0.15)
				)
				(justify left bottom mirror)
			)
		)
		(fp_text user "License: Apache-2.0"
			(at -0.9656 -4.369 180)
			(layer "B.Fab")
			(effects
				(font
					(size 0.7 0.7)
					(thickness 0.15)
				)
				(justify left bottom mirror)
			)
		)
		(pad "1" smd roundrect
			(at -0.5 0 270)
			(size 0.6 0.6)
			(layers "B.Cu" "B.Mask" "B.Paste")
			(roundrect_rratio 0.25)
			(net 1 "GND")
			(pintype "passive")
		)
		(pad "2" smd roundrect
			(at 0.498 0)
			(size 0.6 0.6)
			(layers "B.Cu" "B.Mask" "B.Paste")
			(roundrect_rratio 0.25)
			(net 797 "+1V8")
			(pintype "passive")
		)
	)
	(footprint "antmicro-footprints:C_0402_1005Metric"
		(layer "B.Cu")
		(at 207.29 154.19 90)
		(descr "Capacitor SMD 0402")
		(tags "capacitor SMD 0402")
		(property "Reference" "C223"
			(at -4.22 0.47 90)
			(layer "B.SilkS")
			(effects
				(font
					(size 0.7 0.7)
					(thickness 0.15)
				)
				(justify right bottom mirror)
			)
		)
		(property "Value" "C_100n_0402"
			(at -1.022927 -2.155213 90)
			(layer "B.Fab")
			(effects
				(font
					(size 0.7 0.7)
					(thickness 0.15)
				)
				(justify right bottom mirror)
			)
		)
		(property "Datasheet" "https://www.murata.com/products/productdetail?partno=GRM155R61H104KE14%23"
			(at 0 0 90)
			(layer "F.Fab")
			(hide yes)
			(effects
				(font
					(size 1.27 1.27)
					(thickness 0.15)
				)
			)
		)
		(property "Manufacturer" "Murata"
			(at 0 0 90)
			(unlocked yes)
			(layer "B.Fab")
			(hide yes)
			(effects
				(font
					(size 1 1)
					(thickness 0.15)
				)
				(justify mirror)
			)
		)
		(property "MPN" "GRM155R61H104KE14D"
			(at 0 0 90)
			(unlocked yes)
			(layer "B.Fab")
			(hide yes)
			(effects
				(font
					(size 1 1)
					(thickness 0.15)
				)
				(justify mirror)
			)
		)
		(property "Val" "100n"
			(at 0 0 90)
			(unlocked yes)
			(layer "B.Fab")
			(hide yes)
			(effects
				(font
					(size 1 1)
					(thickness 0.15)
				)
				(justify mirror)
			)
		)
		(property "License" "Apache-2.0"
			(at 0 0 90)
			(unlocked yes)
			(layer "B.Fab")
			(hide yes)
			(effects
				(font
					(size 1 1)
					(thickness 0.15)
				)
				(justify mirror)
			)
		)
		(property "Author" "Antmicro"
			(at 0 0 90)
			(unlocked yes)
			(layer "B.Fab")
			(hide yes)
			(effects
				(font
					(size 1 1)
					(thickness 0.15)
				)
				(justify mirror)
			)
		)
		(property "Voltage" "50V"
			(at 0 0 90)
			(unlocked yes)
			(layer "B.Fab")
			(hide yes)
			(effects
				(font
					(size 1 1)
					(thickness 0.15)
				)
				(justify mirror)
			)
		)
		(property "Dielectric" "X5R"
			(at 0 0 90)
			(unlocked yes)
			(layer "B.Fab")
			(hide yes)
			(effects
				(font
					(size 1 1)
					(thickness 0.15)
				)
				(justify mirror)
			)
		)
		(sheetname "/FPGA Config/")
		(sheetfile "fpga-config.kicad_sch")
		(attr smd)
		(fp_rect
			(start -0.925 0.47)
			(end 0.925 -0.47)
			(stroke
				(width 0.05)
				(type default)
			)
			(fill no)
			(layer "B.CrtYd")
		)
		(fp_line
			(start 0.504 -0.248)
			(end -0.494 -0.248)
			(stroke
				(width 0.15)
				(type solid)
			)
			(layer "B.Fab")
		)
		(fp_line
			(start -0.494 -0.248)
			(end -0.494 0.25)
			(stroke
				(width 0.15)
				(type solid)
			)
			(layer "B.Fab")
		)
		(fp_line
			(start 0.504 0.25)
			(end 0.504 -0.248)
			(stroke
				(width 0.15)
				(type solid)
			)
			(layer "B.Fab")
		)
		(fp_line
			(start -0.494 0.25)
			(end 0.504 0.25)
			(stroke
				(width 0.15)
				(type solid)
			)
			(layer "B.Fab")
		)
		(fp_text user "License: Apache-2.0"
			(at -0.939 -5.799 270)
			(layer "B.Fab")
			(effects
				(font
					(size 0.7 0.7)
					(thickness 0.15)
				)
				(justify left bottom mirror)
			)
		)
		(fp_text user "Author: Antmicro"
			(at -0.939 -3.399 270)
			(layer "B.Fab")
			(effects
				(font
					(size 0.7 0.7)
					(thickness 0.15)
				)
				(justify left bottom mirror)
			)
		)
		(fp_text user "${REFERENCE}"
			(at -0.939 -4.599 270)
			(layer "B.Fab")
			(effects
				(font
					(size 0.7 0.7)
					(thickness 0.15)
				)
				(justify left bottom mirror)
			)
		)
		(pad "1" smd roundrect
			(at -0.48 0 90)
			(size 0.59 0.64)
			(layers "B.Cu" "B.Mask" "B.Paste")
			(roundrect_rratio 0.25)
			(net 1 "GND")
			(pintype "passive")
		)
		(pad "2" smd roundrect
			(at 0.48 0 90)
			(size 0.59 0.64)
			(layers "B.Cu" "B.Mask" "B.Paste")
			(roundrect_rratio 0.25)
			(net 151 "+3V3")
			(pintype "passive")
		)
	)
	(footprint "antmicro-footprints:R_0402_1005Metric"
		(layer "B.Cu")
		(at 243.05 101.6 180)
		(descr "Resistor SMD 0402")
		(tags "resistor SMD 0402")
		(property "Reference" "R246"
			(at 0.87 -0.38 0)
			(layer "B.SilkS")
			(effects
				(font
					(size 0.7 0.7)
					(thickness 0.15)
				)
				(justify left bottom mirror)
			)
		)
		(property "Value" "R_330R_0402"
			(at -1.011843 -1.772047 0)
			(layer "B.Fab")
			(effects
				(font
					(size 0.7 0.7)
					(thickness 0.15)
				)
				(justify left bottom mirror)
			)
		)
		(property "Datasheet" "https://www.bourns.com/docs/product-datasheets/cr.pdf"
			(at 0 0 0)
			(layer "F.Fab")
			(hide yes)
			(effects
				(font
					(size 1.27 1.27)
					(thickness 0.15)
				)
			)
		)
		(property "MPN" "CR0402-FX-3300GLF"
			(at 0 0 180)
			(unlocked yes)
			(layer "B.Fab")
			(hide yes)
			(effects
				(font
					(size 1 1)
					(thickness 0.15)
				)
				(justify mirror)
			)
		)
		(property "Manufacturer" "Bourns"
			(at 0 0 180)
			(unlocked yes)
			(layer "B.Fab")
			(hide yes)
			(effects
				(font
					(size 1 1)
					(thickness 0.15)
				)
				(justify mirror)
			)
		)
		(property "License" "Apache-2.0"
			(at 0 0 180)
			(unlocked yes)
			(layer "B.Fab")
			(hide yes)
			(effects
				(font
					(size 1 1)
					(thickness 0.15)
				)
				(justify mirror)
			)
		)
		(property "Author" "Antmicro"
			(at 0 0 180)
			(unlocked yes)
			(layer "B.Fab")
			(hide yes)
			(effects
				(font
					(size 1 1)
					(thickness 0.15)
				)
				(justify mirror)
			)
		)
		(property "Val" "330R"
			(at 0 0 180)
			(unlocked yes)
			(layer "B.Fab")
			(hide yes)
			(effects
				(font
					(size 1 1)
					(thickness 0.15)
				)
				(justify mirror)
			)
		)
		(property "Tolerance" "1%"
			(at 0 0 180)
			(unlocked yes)
			(layer "B.Fab")
			(hide yes)
			(effects
				(font
					(size 1 1)
					(thickness 0.15)
				)
				(justify mirror)
			)
		)
		(sheetname "/DDR5 RDIMM/")
		(sheetfile "ddr5-rdimm.kicad_sch")
		(attr smd)
		(fp_rect
			(start -0.925 0.47)
			(end 0.925 -0.47)
			(stroke
				(width 0.05)
				(type default)
			)
			(fill no)
			(layer "B.CrtYd")
		)
		(fp_rect
			(start -0.5 0.25)
			(end 0.5 -0.25)
			(stroke
				(width 0.15)
				(type solid)
			)
			(fill no)
			(layer "B.Fab")
		)
		(fp_text user "License: Apache-2.0"
			(at -0.95 -5.169 0)
			(layer "B.Fab")
			(effects
				(font
					(size 0.7 0.7)
					(thickness 0.15)
				)
				(justify left bottom mirror)
			)
		)
		(fp_text user "Author: Antmicro"
			(at -0.95 -4.169 0)
			(layer "B.Fab")
			(effects
				(font
					(size 0.7 0.7)
					(thickness 0.15)
				)
				(justify left bottom mirror)
			)
		)
		(fp_text user "${REFERENCE}"
			(at -0.95 -3.168 0)
			(layer "B.Fab")
			(effects
				(font
					(size 0.7 0.7)
					(thickness 0.15)
				)
				(justify left bottom mirror)
			)
		)
		(pad "1" smd roundrect
			(at -0.48 0 180)
			(size 0.59 0.64)
			(layers "B.Cu" "B.Mask" "B.Paste")
			(roundrect_rratio 0.25)
			(net 1 "GND")
			(pintype "passive")
		)
		(pad "2" smd roundrect
			(at 0.48 0 180)
			(size 0.59 0.64)
			(layers "B.Cu" "B.Mask" "B.Paste")
			(roundrect_rratio 0.25)
			(net 805 "Net-(D22-C)")
			(pintype "passive")
		)
	)
)
